(kicad_pcb
	(version 20260206)
	(generator "pcbnew")
	(generator_version "10.0")
	(general
		(thickness 1.6)
		(legacy_teardrops no)
	)
	(paper "A4")
	(title_block
		(title "04192023_DAF0TMB3IC0_F0TG_MB_C_brd_V02_OCP.brd")
		(comment 1 "Grand Teton / footprints 5692-5698 of 8354")
	)
	(layers
		(0 "F.Cu" signal "TOP")
		(4 "In1.Cu" signal "GND")
		(6 "In2.Cu" signal "IN1")
		(8 "In3.Cu" signal "GND1")
		(10 "In4.Cu" signal "IN2")
		(12 "In5.Cu" signal "GND2")
		(14 "In6.Cu" signal "IN3")
		(16 "In7.Cu" signal "GND3")
		(18 "In8.Cu" signal "VCC")
		(20 "In9.Cu" signal "VCC1")
		(22 "In10.Cu" signal "GND4")
		(24 "In11.Cu" signal "IN4")
		(26 "In12.Cu" signal "GND5")
		(28 "In13.Cu" signal "IN5")
		(30 "In14.Cu" signal "GND6")
		(32 "In15.Cu" signal "IN6")
		(34 "In16.Cu" signal "GND7")
		(2 "B.Cu" signal "BOTTOM")
		(9 "F.Adhes" user "F.Adhesive")
		(11 "B.Adhes" user "B.Adhesive")
		(13 "F.Paste" user "Package Geometry/Pastemask Top")
		(15 "B.Paste" user "Package Geometry/Pastemask Bottom")
		(5 "F.SilkS" user "Ref Des/Silkscreen Top")
		(7 "B.SilkS" user "Ref Des/Silkscreen Bottom")
		(1 "F.Mask" user "Board Geometry/Soldermask Top")
		(3 "B.Mask" user "Board Geometry/Soldermask Bottom")
		(17 "Dwgs.User" user "User.Drawings")
		(19 "Cmts.User" user "User.Comments")
		(21 "Eco1.User" user "User.Eco1")
		(23 "Eco2.User" user "User.Eco2")
		(25 "Edge.Cuts" user "Board Geometry/Outline")
		(27 "Margin" user)
		(31 "F.CrtYd" user "Package Geometry/Place Bound Top")
		(29 "B.CrtYd" user "Package Geometry/Place Bound Bottom")
		(35 "F.Fab" user "Ref Des/Assembly Top")
		(33 "B.Fab" user "Ref Des/Assembly Bottom")
	)
	(footprint ""
		(layer "B.Cu")
		(at 193.929 -100.294948 90)
		(property "Reference" "R1304"
			(at 0 0 90)
			(layer "B.SilkS")
			(hide yes)
			(effects
				(font
					(size 1.27 1.27)
				)
				(justify mirror)
			)
		)
		(property "Value" ""
			(at 0 0 90)
			(layer "B.Fab")
			(effects
				(font
					(size 1.27 1.27)
				)
				(justify mirror)
			)
		)
		(duplicate_pad_numbers_are_jumpers no)
		(fp_line
			(start 0.7874 -0.4064)
			(end -0.7874 -0.4064)
			(stroke
				(width 0.1524)
				(type default)
			)
			(layer "B.SilkS")
		)
		(fp_line
			(start -0.7874 -0.4064)
			(end -0.7874 0.4064)
			(stroke
				(width 0.1524)
				(type default)
			)
			(layer "B.SilkS")
		)
		(fp_line
			(start 0.7874 0.4064)
			(end 0.7874 -0.4064)
			(stroke
				(width 0.1524)
				(type default)
			)
			(layer "B.SilkS")
		)
		(fp_line
			(start -0.7874 0.4064)
			(end 0.7874 0.4064)
			(stroke
				(width 0.1524)
				(type default)
			)
			(layer "B.SilkS")
		)
		(fp_line
			(start 0.67945 -0.305054)
			(end 0.12065 -0.305054)
			(stroke
				(width 0.1)
				(type default)
			)
			(layer "B.Fab")
		)
		(fp_line
			(start 0.12065 -0.305054)
			(end 0.12065 -0.2794)
			(stroke
				(width 0.1)
				(type default)
			)
			(layer "B.Fab")
		)
		(fp_line
			(start -0.12065 -0.3048)
			(end -0.67945 -0.3048)
			(stroke
				(width 0.1)
				(type default)
			)
			(layer "B.Fab")
		)
		(fp_line
			(start -0.67945 -0.3048)
			(end -0.67945 0.3048)
			(stroke
				(width 0.1)
				(type default)
			)
			(layer "B.Fab")
		)
		(fp_line
			(start 0.12065 -0.2794)
			(end -0.12065 -0.2794)
			(stroke
				(width 0.1)
				(type default)
			)
			(layer "B.Fab")
		)
		(fp_line
			(start -0.12065 -0.2794)
			(end -0.12065 -0.3048)
			(stroke
				(width 0.1)
				(type default)
			)
			(layer "B.Fab")
		)
		(fp_line
			(start 0.12065 0.2794)
			(end 0.12065 0.3048)
			(stroke
				(width 0.1)
				(type default)
			)
			(layer "B.Fab")
		)
		(fp_line
			(start -0.120396 0.2794)
			(end 0.12065 0.2794)
			(stroke
				(width 0.1)
				(type default)
			)
			(layer "B.Fab")
		)
		(fp_line
			(start 0.67945 0.3048)
			(end 0.67945 -0.305054)
			(stroke
				(width 0.1)
				(type default)
			)
			(layer "B.Fab")
		)
		(fp_line
			(start 0.12065 0.3048)
			(end 0.67945 0.3048)
			(stroke
				(width 0.1)
				(type default)
			)
			(layer "B.Fab")
		)
		(fp_line
			(start -0.120396 0.3048)
			(end -0.120396 0.2794)
			(stroke
				(width 0.1)
				(type default)
			)
			(layer "B.Fab")
		)
		(fp_line
			(start -0.67945 0.3048)
			(end -0.120396 0.3048)
			(stroke
				(width 0.1)
				(type default)
			)
			(layer "B.Fab")
		)
		(pad "1" smd circle
			(at 0.40005 0 270)
			(size 0 0)
			(layers "B.Cu" "B.Mask" "B.Paste")
			(net "E1S_0_PRSNT_N")
		)
		(pad "2" smd circle
			(at -0.40005 0 270)
			(size 0 0)
			(layers "B.Cu" "B.Mask" "B.Paste")
			(net "P3V3_AUX")
		)
	)
	(footprint ""
		(layer "B.Cu")
		(at 51.328574 -422.777666)
		(property "Reference" "R3511"
			(at 0 0 0)
			(layer "B.SilkS")
			(hide yes)
			(effects
				(font
					(size 1.27 1.27)
				)
				(justify mirror)
			)
		)
		(property "Value" ""
			(at 0 0 0)
			(layer "B.Fab")
			(effects
				(font
					(size 1.27 1.27)
				)
				(justify mirror)
			)
		)
		(duplicate_pad_numbers_are_jumpers no)
		(fp_line
			(start -0.7874 -0.4064)
			(end -0.7874 0.4064)
			(stroke
				(width 0.1524)
				(type default)
			)
			(layer "B.SilkS")
		)
		(fp_line
			(start -0.7874 0.4064)
			(end 0.7874 0.4064)
			(stroke
				(width 0.1524)
				(type default)
			)
			(layer "B.SilkS")
		)
		(fp_line
			(start 0.7874 -0.4064)
			(end -0.7874 -0.4064)
			(stroke
				(width 0.1524)
				(type default)
			)
			(layer "B.SilkS")
		)
		(fp_line
			(start 0.7874 0.4064)
			(end 0.7874 -0.4064)
			(stroke
				(width 0.1524)
				(type default)
			)
			(layer "B.SilkS")
		)
		(fp_line
			(start -0.67945 -0.3048)
			(end -0.67945 0.3048)
			(stroke
				(width 0.1)
				(type default)
			)
			(layer "B.Fab")
		)
		(fp_line
			(start -0.67945 0.3048)
			(end -0.120396 0.3048)
			(stroke
				(width 0.1)
				(type default)
			)
			(layer "B.Fab")
		)
		(fp_line
			(start -0.12065 -0.3048)
			(end -0.67945 -0.3048)
			(stroke
				(width 0.1)
				(type default)
			)
			(layer "B.Fab")
		)
		(fp_line
			(start -0.12065 -0.2794)
			(end -0.12065 -0.3048)
			(stroke
				(width 0.1)
				(type default)
			)
			(layer "B.Fab")
		)
		(fp_line
			(start -0.120396 0.2794)
			(end 0.12065 0.2794)
			(stroke
				(width 0.1)
				(type default)
			)
			(layer "B.Fab")
		)
		(fp_line
			(start -0.120396 0.3048)
			(end -0.120396 0.2794)
			(stroke
				(width 0.1)
				(type default)
			)
			(layer "B.Fab")
		)
		(fp_line
			(start 0.12065 -0.305054)
			(end 0.12065 -0.2794)
			(stroke
				(width 0.1)
				(type default)
			)
			(layer "B.Fab")
		)
		(fp_line
			(start 0.12065 -0.2794)
			(end -0.12065 -0.2794)
			(stroke
				(width 0.1)
				(type default)
			)
			(layer "B.Fab")
		)
		(fp_line
			(start 0.12065 0.2794)
			(end 0.12065 0.3048)
			(stroke
				(width 0.1)
				(type default)
			)
			(layer "B.Fab")
		)
		(fp_line
			(start 0.12065 0.3048)
			(end 0.67945 0.3048)
			(stroke
				(width 0.1)
				(type default)
			)
			(layer "B.Fab")
		)
		(fp_line
			(start 0.67945 -0.305054)
			(end 0.12065 -0.305054)
			(stroke
				(width 0.1)
				(type default)
			)
			(layer "B.Fab")
		)
		(fp_line
			(start 0.67945 0.3048)
			(end 0.67945 -0.305054)
			(stroke
				(width 0.1)
				(type default)
			)
			(layer "B.Fab")
		)
		(pad "1" smd circle
			(at 0.40005 0 180)
			(size 0 0)
			(layers "B.Cu" "B.Mask" "B.Paste")
			(net "GPU_FPGA_READY")
		)
		(pad "2" smd circle
			(at -0.40005 0 180)
			(size 0 0)
			(layers "B.Cu" "B.Mask" "B.Paste")
			(net "GND")
		)
	)
	(footprint ""
		(layer "B.Cu")
		(at 383.69113 -398.942052 90)
		(property "Reference" "C1034"
			(at 0 0 90)
			(layer "B.SilkS")
			(hide yes)
			(effects
				(font
					(size 1.27 1.27)
				)
				(justify mirror)
			)
		)
		(property "Value" ""
			(at 0 0 90)
			(layer "B.Fab")
			(effects
				(font
					(size 1.27 1.27)
				)
				(justify mirror)
			)
		)
		(duplicate_pad_numbers_are_jumpers no)
		(fp_line
			(start 0.7874 -0.4064)
			(end -0.7874 -0.4064)
			(stroke
				(width 0.1524)
				(type default)
			)
			(layer "B.SilkS")
		)
		(fp_line
			(start -0.7874 -0.4064)
			(end -0.7874 0.4064)
			(stroke
				(width 0.1524)
				(type default)
			)
			(layer "B.SilkS")
		)
		(fp_line
			(start 0.7874 0.4064)
			(end 0.7874 -0.4064)
			(stroke
				(width 0.1524)
				(type default)
			)
			(layer "B.SilkS")
		)
		(fp_line
			(start -0.7874 0.4064)
			(end 0.7874 0.4064)
			(stroke
				(width 0.1524)
				(type default)
			)
			(layer "B.SilkS")
		)
		(fp_line
			(start 0.67945 -0.305054)
			(end 0.12065 -0.305054)
			(stroke
				(width 0.1)
				(type default)
			)
			(layer "B.Fab")
		)
		(fp_line
			(start 0.12065 -0.305054)
			(end 0.12065 -0.2794)
			(stroke
				(width 0.1)
				(type default)
			)
			(layer "B.Fab")
		)
		(fp_line
			(start -0.12065 -0.3048)
			(end -0.67945 -0.3048)
			(stroke
				(width 0.1)
				(type default)
			)
			(layer "B.Fab")
		)
		(fp_line
			(start -0.67945 -0.3048)
			(end -0.67945 0.3048)
			(stroke
				(width 0.1)
				(type default)
			)
			(layer "B.Fab")
		)
		(fp_line
			(start 0.12065 -0.2794)
			(end -0.12065 -0.2794)
			(stroke
				(width 0.1)
				(type default)
			)
			(layer "B.Fab")
		)
		(fp_line
			(start -0.12065 -0.2794)
			(end -0.12065 -0.3048)
			(stroke
				(width 0.1)
				(type default)
			)
			(layer "B.Fab")
		)
		(fp_line
			(start 0.12065 0.2794)
			(end 0.12065 0.3048)
			(stroke
				(width 0.1)
				(type default)
			)
			(layer "B.Fab")
		)
		(fp_line
			(start -0.120396 0.2794)
			(end 0.12065 0.2794)
			(stroke
				(width 0.1)
				(type default)
			)
			(layer "B.Fab")
		)
		(fp_line
			(start 0.67945 0.3048)
			(end 0.67945 -0.305054)
			(stroke
				(width 0.1)
				(type default)
			)
			(layer "B.Fab")
		)
		(fp_line
			(start 0.12065 0.3048)
			(end 0.67945 0.3048)
			(stroke
				(width 0.1)
				(type default)
			)
			(layer "B.Fab")
		)
		(fp_line
			(start -0.120396 0.3048)
			(end -0.120396 0.2794)
			(stroke
				(width 0.1)
				(type default)
			)
			(layer "B.Fab")
		)
		(fp_line
			(start -0.67945 0.3048)
			(end -0.120396 0.3048)
			(stroke
				(width 0.1)
				(type default)
			)
			(layer "B.Fab")
		)
		(pad "1" smd circle
			(at 0.40005 0 270)
			(size 0 0)
			(layers "B.Cu" "B.Mask" "B.Paste")
			(net "P0V9_CPU0_RT3_2A")
		)
		(pad "2" smd circle
			(at -0.40005 0 270)
			(size 0 0)
			(layers "B.Cu" "B.Mask" "B.Paste")
			(net "GND")
		)
	)
	(footprint ""
		(layer "B.Cu")
		(at 58.178446 -386.766562 90)
		(property "Reference" "C125"
			(at 0 0 90)
			(layer "B.SilkS")
			(hide yes)
			(effects
				(font
					(size 1.27 1.27)
				)
				(justify mirror)
			)
		)
		(property "Value" ""
			(at 0 0 90)
			(layer "B.Fab")
			(effects
				(font
					(size 1.27 1.27)
				)
				(justify mirror)
			)
		)
		(duplicate_pad_numbers_are_jumpers no)
		(fp_line
			(start 0.299974 -0.150114)
			(end -0.299974 -0.150114)
			(stroke
				(width 0.1)
				(type default)
			)
			(layer "B.Fab")
		)
		(fp_line
			(start -0.299974 -0.150114)
			(end -0.299974 0.150114)
			(stroke
				(width 0.1)
				(type default)
			)
			(layer "B.Fab")
		)
		(fp_line
			(start 0.299974 0.150114)
			(end 0.299974 -0.150114)
			(stroke
				(width 0.1)
				(type default)
			)
			(layer "B.Fab")
		)
		(fp_line
			(start -0.299974 0.150114)
			(end 0.299974 0.150114)
			(stroke
				(width 0.1)
				(type default)
			)
			(layer "B.Fab")
		)
		(pad "1" smd rect
			(at 0.2667 0 270)
			(size 0.3048 0.381)
			(layers "B.Cu" "B.Mask" "B.Paste")
			(net "P1V8_CPU1_RT0_1A_1D")
		)
		(pad "2" smd rect
			(at -0.2667 0 270)
			(size 0.3048 0.381)
			(layers "B.Cu" "B.Mask" "B.Paste")
			(net "GND")
		)
	)
	(footprint ""
		(layer "B.Cu")
		(at 15.433294 -110.987586 90)
		(property "Reference" "C5234"
			(at 0 0 90)
			(layer "B.SilkS")
			(hide yes)
			(effects
				(font
					(size 1.27 1.27)
				)
				(justify mirror)
			)
		)
		(property "Value" ""
			(at 0 0 90)
			(layer "B.Fab")
			(effects
				(font
					(size 1.27 1.27)
				)
				(justify mirror)
			)
		)
		(duplicate_pad_numbers_are_jumpers no)
		(fp_line
			(start 0.7874 -0.4064)
			(end -0.7874 -0.4064)
			(stroke
				(width 0.1524)
				(type default)
			)
			(layer "B.SilkS")
		)
		(fp_line
			(start -0.7874 -0.4064)
			(end -0.7874 0.4064)
			(stroke
				(width 0.1524)
				(type default)
			)
			(layer "B.SilkS")
		)
		(fp_line
			(start 0.7874 0.4064)
			(end 0.7874 -0.4064)
			(stroke
				(width 0.1524)
				(type default)
			)
			(layer "B.SilkS")
		)
		(fp_line
			(start -0.7874 0.4064)
			(end 0.7874 0.4064)
			(stroke
				(width 0.1524)
				(type default)
			)
			(layer "B.SilkS")
		)
		(fp_line
			(start 0.67945 -0.305054)
			(end 0.12065 -0.305054)
			(stroke
				(width 0.1)
				(type default)
			)
			(layer "B.Fab")
		)
		(fp_line
			(start 0.12065 -0.305054)
			(end 0.12065 -0.2794)
			(stroke
				(width 0.1)
				(type default)
			)
			(layer "B.Fab")
		)
		(fp_line
			(start -0.12065 -0.3048)
			(end -0.67945 -0.3048)
			(stroke
				(width 0.1)
				(type default)
			)
			(layer "B.Fab")
		)
		(fp_line
			(start -0.67945 -0.3048)
			(end -0.67945 0.3048)
			(stroke
				(width 0.1)
				(type default)
			)
			(layer "B.Fab")
		)
		(fp_line
			(start 0.12065 -0.2794)
			(end -0.12065 -0.2794)
			(stroke
				(width 0.1)
				(type default)
			)
			(layer "B.Fab")
		)
		(fp_line
			(start -0.12065 -0.2794)
			(end -0.12065 -0.3048)
			(stroke
				(width 0.1)
				(type default)
			)
			(layer "B.Fab")
		)
		(fp_line
			(start 0.12065 0.2794)
			(end 0.12065 0.3048)
			(stroke
				(width 0.1)
				(type default)
			)
			(layer "B.Fab")
		)
		(fp_line
			(start -0.120396 0.2794)
			(end 0.12065 0.2794)
			(stroke
				(width 0.1)
				(type default)
			)
			(layer "B.Fab")
		)
		(fp_line
			(start 0.67945 0.3048)
			(end 0.67945 -0.305054)
			(stroke
				(width 0.1)
				(type default)
			)
			(layer "B.Fab")
		)
		(fp_line
			(start 0.12065 0.3048)
			(end 0.67945 0.3048)
			(stroke
				(width 0.1)
				(type default)
			)
			(layer "B.Fab")
		)
		(fp_line
			(start -0.120396 0.3048)
			(end -0.120396 0.2794)
			(stroke
				(width 0.1)
				(type default)
			)
			(layer "B.Fab")
		)
		(fp_line
			(start -0.67945 0.3048)
			(end -0.120396 0.3048)
			(stroke
				(width 0.1)
				(type default)
			)
			(layer "B.Fab")
		)
		(pad "1" smd circle
			(at 0.40005 0 270)
			(size 0 0)
			(layers "B.Cu" "B.Mask" "B.Paste")
			(net "P3V3_AUX")
		)
		(pad "2" smd circle
			(at -0.40005 0 270)
			(size 0 0)
			(layers "B.Cu" "B.Mask" "B.Paste")
			(net "GND")
		)
	)
	(footprint ""
		(layer "B.Cu")
		(at 101.894386 -262.703564)
		(property "Reference" "C2465"
			(at 0 0 0)
			(layer "B.SilkS")
			(hide yes)
			(effects
				(font
					(size 1.27 1.27)
				)
				(justify mirror)
			)
		)
		(property "Value" ""
			(at 0 0 0)
			(layer "B.Fab")
			(effects
				(font
					(size 1.27 1.27)
				)
				(justify mirror)
			)
		)
		(duplicate_pad_numbers_are_jumpers no)
		(fp_line
			(start -0.7874 -0.4064)
			(end -0.7874 0.4064)
			(stroke
				(width 0.1524)
				(type default)
			)
			(layer "B.SilkS")
		)
		(fp_line
			(start -0.7874 0.4064)
			(end 0.7874 0.4064)
			(stroke
				(width 0.1524)
				(type default)
			)
			(layer "B.SilkS")
		)
		(fp_line
			(start 0.7874 -0.4064)
			(end -0.7874 -0.4064)
			(stroke
				(width 0.1524)
				(type default)
			)
			(layer "B.SilkS")
		)
		(fp_line
			(start 0.7874 0.4064)
			(end 0.7874 -0.4064)
			(stroke
				(width 0.1524)
				(type default)
			)
			(layer "B.SilkS")
		)
		(fp_line
			(start -0.67945 -0.3048)
			(end -0.67945 0.3048)
			(stroke
				(width 0.1)
				(type default)
			)
			(layer "B.Fab")
		)
		(fp_line
			(start -0.67945 0.3048)
			(end -0.120396 0.3048)
			(stroke
				(width 0.1)
				(type default)
			)
			(layer "B.Fab")
		)
		(fp_line
			(start -0.12065 -0.3048)
			(end -0.67945 -0.3048)
			(stroke
				(width 0.1)
				(type default)
			)
			(layer "B.Fab")
		)
		(fp_line
			(start -0.12065 -0.2794)
			(end -0.12065 -0.3048)
			(stroke
				(width 0.1)
				(type default)
			)
			(layer "B.Fab")
		)
		(fp_line
			(start -0.120396 0.2794)
			(end 0.12065 0.2794)
			(stroke
				(width 0.1)
				(type default)
			)
			(layer "B.Fab")
		)
		(fp_line
			(start -0.120396 0.3048)
			(end -0.120396 0.2794)
			(stroke
				(width 0.1)
				(type default)
			)
			(layer "B.Fab")
		)
		(fp_line
			(start 0.12065 -0.305054)
			(end 0.12065 -0.2794)
			(stroke
				(width 0.1)
				(type default)
			)
			(layer "B.Fab")
		)
		(fp_line
			(start 0.12065 -0.2794)
			(end -0.12065 -0.2794)
			(stroke
				(width 0.1)
				(type default)
			)
			(layer "B.Fab")
		)
		(fp_line
			(start 0.12065 0.2794)
			(end 0.12065 0.3048)
			(stroke
				(width 0.1)
				(type default)
			)
			(layer "B.Fab")
		)
		(fp_line
			(start 0.12065 0.3048)
			(end 0.67945 0.3048)
			(stroke
				(width 0.1)
				(type default)
			)
			(layer "B.Fab")
		)
		(fp_line
			(start 0.67945 -0.305054)
			(end 0.12065 -0.305054)
			(stroke
				(width 0.1)
				(type default)
			)
			(layer "B.Fab")
		)
		(fp_line
			(start 0.67945 0.3048)
			(end 0.67945 -0.305054)
			(stroke
				(width 0.1)
				(type default)
			)
			(layer "B.Fab")
		)
		(pad "1" smd circle
			(at 0.40005 0 180)
			(size 0 0)
			(layers "B.Cu" "B.Mask" "B.Paste")
			(net "PVDDCR_SOC_P1")
		)
		(pad "2" smd circle
			(at -0.40005 0 180)
			(size 0 0)
			(layers "B.Cu" "B.Mask" "B.Paste")
			(net "GND")
		)
	)
	(footprint ""
		(layer "B.Cu")
		(at 197.93712 -331.027786 -90)
		(property "Reference" "PC135"
			(at 0 0 90)
			(layer "B.SilkS")
			(hide yes)
			(effects
				(font
					(size 1.27 1.27)
				)
				(justify mirror)
			)
		)
		(property "Value" ""
			(at 0 0 90)
			(layer "B.Fab")
			(effects
				(font
					(size 1.27 1.27)
				)
				(justify mirror)
			)
		)
		(duplicate_pad_numbers_are_jumpers no)
		(fp_line
			(start -1.524 0.762)
			(end 1.524 0.762)
			(stroke
				(width 0.1524)
				(type default)
			)
			(layer "B.SilkS")
		)
		(fp_line
			(start 1.524 0.762)
			(end 1.524 -0.762)
			(stroke
				(width 0.1524)
				(type default)
			)
			(layer "B.SilkS")
		)
		(fp_line
			(start -1.524 -0.762)
			(end -1.524 0.762)
			(stroke
				(width 0.1524)
				(type default)
			)
			(layer "B.SilkS")
		)
		(fp_line
			(start 1.524 -0.762)
			(end -1.524 -0.762)
			(stroke
				(width 0.1524)
				(type default)
			)
			(layer "B.SilkS")
		)
		(fp_line
			(start -1.1049 0.724916)
			(end -1.1049 -0.724916)
			(stroke
				(width 0.1)
				(type default)
			)
			(layer "B.Fab")
		)
		(fp_line
			(start 1.1049 0.724916)
			(end -1.1049 0.724916)
			(stroke
				(width 0.1)
				(type default)
			)
			(layer "B.Fab")
		)
		(fp_line
			(start -1.1049 -0.724916)
			(end 1.1049 -0.724916)
			(stroke
				(width 0.1)
				(type default)
			)
			(layer "B.Fab")
		)
		(fp_line
			(start 1.1049 -0.724916)
			(end 1.1049 0.724916)
			(stroke
				(width 0.1)
				(type default)
			)
			(layer "B.Fab")
		)
		(pad "1" smd rect
			(at 0.889 0 270)
			(size 1.016 1.27)
			(layers "B.Cu" "B.Mask" "B.Paste")
			(net "PVDD_33_S5")
		)
		(pad "2" smd rect
			(at -0.889 0 270)
			(size 1.016 1.27)
			(layers "B.Cu" "B.Mask" "B.Paste")
			(net "GND")
		)
	)
)
